# S9S_MB_2U (Grand Teton) — schematic netlist excerpt (pin names and nets, part order shuffled) for the footprints in the layout excerpt that follows; sources: Cadence DE-HDL packaged netlist, KiCad conversion of 03242023_DA0F0TMBIJ0_F0T_Motherboard_J_brd_V01_OCP.brd

C2289  Q_CAP  0.1UF 6.3V 10% X6S  pkg C0201  page 169 : A = USB3_PCH_TX_BUF_DP<4> ; B = USB3_PCH_TX_BUF_C_DP<4>
R3118  Q_RES  86.6K 1% EMPTY  pkg 0402LF  page 259 : A = P3V3_AUX_EN ; B = GND
PC306_P0_2  Q_CAP  22UF 16V 20% X6S  pkg C0805  page 267 : A = SW_P12V_PVCCIN_CPU0_FLT ; B = GND

(kicad_pcb
	(version 20260206)
	(generator "pcbnew")
	(generator_version "10.0")
	(general
		(thickness 1.6)
		(legacy_teardrops no)
	)
	(paper "A4")
	(title_block
		(title "03242023_DA0F0TMBIJ0_F0T_Motherboard_J_brd_V01_OCP.brd")
		(comment 1 "Grand Teton / footprints 4187-4189 of 6105")
	)
	(layers
		(0 "F.Cu" signal "TOP")
		(4 "In1.Cu" signal "GND")
		(6 "In2.Cu" signal "IN1")
		(8 "In3.Cu" signal "GND1")
		(10 "In4.Cu" signal "IN2")
		(12 "In5.Cu" signal "GND2")
		(14 "In6.Cu" signal "IN3")
		(16 "In7.Cu" signal "GND3")
		(18 "In8.Cu" signal "VCC")
		(20 "In9.Cu" signal "VCC1")
		(22 "In10.Cu" signal "GND4")
		(24 "In11.Cu" signal "IN4")
		(26 "In12.Cu" signal "GND5")
		(28 "In13.Cu" signal "IN5")
		(30 "In14.Cu" signal "GND6")
		(32 "In15.Cu" signal "IN6")
		(34 "In16.Cu" signal "GND7")
		(2 "B.Cu" signal "BOTTOM")
		(9 "F.Adhes" user "F.Adhesive")
		(11 "B.Adhes" user "B.Adhesive")
		(13 "F.Paste" user "Package Geometry/Pastemask Top")
		(15 "B.Paste" user "Package Geometry/Pastemask Bottom")
		(5 "F.SilkS" user "Ref Des/Silkscreen Top")
		(7 "B.SilkS" user "Ref Des/Silkscreen Bottom")
		(1 "F.Mask" user "Board Geometry/Soldermask Top")
		(3 "B.Mask" user "Board Geometry/Soldermask Bottom")
		(17 "Dwgs.User" user "User.Drawings")
		(19 "Cmts.User" user "User.Comments")
		(21 "Eco1.User" user "User.Eco1")
		(23 "Eco2.User" user "User.Eco2")
		(25 "Edge.Cuts" user "Board Geometry/Outline")
		(27 "Margin" user)
		(31 "F.CrtYd" user "Package Geometry/Place Bound Top")
		(29 "B.CrtYd" user "Package Geometry/Place Bound Bottom")
		(35 "F.Fab" user "Ref Des/Assembly Top")
		(33 "B.Fab" user "Ref Des/Assembly Bottom")
	)
	(footprint ""
		(layer "B.Cu")
		(at 450.732398 -76.719176 90)
		(property "Reference" "R3118"
			(at 0 0 90)
			(layer "B.SilkS")
			(hide yes)
			(effects
				(font
					(size 1.27 1.27)
				)
				(justify mirror)
			)
		)
		(property "Value" ""
			(at 0 0 90)
			(layer "B.Fab")
			(effects
				(font
					(size 1.27 1.27)
				)
				(justify mirror)
			)
		)
		(duplicate_pad_numbers_are_jumpers no)
		(fp_line
			(start 0.7874 -0.4064)
			(end -0.7874 -0.4064)
			(stroke
				(width 0.1524)
				(type default)
			)
			(layer "B.SilkS")
		)
		(fp_line
			(start -0.7874 -0.4064)
			(end -0.7874 0.4064)
			(stroke
				(width 0.1524)
				(type default)
			)
			(layer "B.SilkS")
		)
		(fp_line
			(start 0.7874 0.4064)
			(end 0.7874 -0.4064)
			(stroke
				(width 0.1524)
				(type default)
			)
			(layer "B.SilkS")
		)
		(fp_line
			(start -0.7874 0.4064)
			(end 0.7874 0.4064)
			(stroke
				(width 0.1524)
				(type default)
			)
			(layer "B.SilkS")
		)
		(fp_line
			(start 0.67945 -0.305054)
			(end 0.12065 -0.305054)
			(stroke
				(width 0.1)
				(type default)
			)
			(layer "B.Fab")
		)
		(fp_line
			(start 0.12065 -0.305054)
			(end 0.12065 -0.2794)
			(stroke
				(width 0.1)
				(type default)
			)
			(layer "B.Fab")
		)
		(fp_line
			(start -0.12065 -0.3048)
			(end -0.67945 -0.3048)
			(stroke
				(width 0.1)
				(type default)
			)
			(layer "B.Fab")
		)
		(fp_line
			(start -0.67945 -0.3048)
			(end -0.67945 0.3048)
			(stroke
				(width 0.1)
				(type default)
			)
			(layer "B.Fab")
		)
		(fp_line
			(start 0.12065 -0.2794)
			(end -0.12065 -0.2794)
			(stroke
				(width 0.1)
				(type default)
			)
			(layer "B.Fab")
		)
		(fp_line
			(start -0.12065 -0.2794)
			(end -0.12065 -0.3048)
			(stroke
				(width 0.1)
				(type default)
			)
			(layer "B.Fab")
		)
		(fp_line
			(start 0.12065 0.2794)
			(end 0.12065 0.3048)
			(stroke
				(width 0.1)
				(type default)
			)
			(layer "B.Fab")
		)
		(fp_line
			(start -0.120396 0.2794)
			(end 0.12065 0.2794)
			(stroke
				(width 0.1)
				(type default)
			)
			(layer "B.Fab")
		)
		(fp_line
			(start 0.67945 0.3048)
			(end 0.67945 -0.305054)
			(stroke
				(width 0.1)
				(type default)
			)
			(layer "B.Fab")
		)
		(fp_line
			(start 0.12065 0.3048)
			(end 0.67945 0.3048)
			(stroke
				(width 0.1)
				(type default)
			)
			(layer "B.Fab")
		)
		(fp_line
			(start -0.120396 0.3048)
			(end -0.120396 0.2794)
			(stroke
				(width 0.1)
				(type default)
			)
			(layer "B.Fab")
		)
		(fp_line
			(start -0.67945 0.3048)
			(end -0.120396 0.3048)
			(stroke
				(width 0.1)
				(type default)
			)
			(layer "B.Fab")
		)
		(pad "1" smd circle
			(at 0.40005 0 270)
			(size 0 0)
			(layers "B.Cu" "B.Mask" "B.Paste")
			(net "P3V3_AUX_EN")
		)
		(pad "2" smd circle
			(at -0.40005 0 270)
			(size 0 0)
			(layers "B.Cu" "B.Mask" "B.Paste")
			(net "GND")
		)
	)
	(footprint ""
		(layer "B.Cu")
		(at 354.219764 -333.639922 90)
		(property "Reference" "PC306_P0_2"
			(at 0 0 90)
			(layer "B.SilkS")
			(hide yes)
			(effects
				(font
					(size 1.27 1.27)
				)
				(justify mirror)
			)
		)
		(property "Value" ""
			(at 0 0 90)
			(layer "B.Fab")
			(effects
				(font
					(size 1.27 1.27)
				)
				(justify mirror)
			)
		)
		(duplicate_pad_numbers_are_jumpers no)
		(fp_line
			(start 1.524 -0.762)
			(end -1.524 -0.762)
			(stroke
				(width 0.1524)
				(type default)
			)
			(layer "B.SilkS")
		)
		(fp_line
			(start -1.524 -0.762)
			(end -1.524 0.762)
			(stroke
				(width 0.1524)
				(type default)
			)
			(layer "B.SilkS")
		)
		(fp_line
			(start 1.524 0.762)
			(end 1.524 -0.762)
			(stroke
				(width 0.1524)
				(type default)
			)
			(layer "B.SilkS")
		)
		(fp_line
			(start -1.524 0.762)
			(end 1.524 0.762)
			(stroke
				(width 0.1524)
				(type default)
			)
			(layer "B.SilkS")
		)
		(fp_line
			(start 1.1049 -0.724916)
			(end 1.1049 0.724916)
			(stroke
				(width 0.1)
				(type default)
			)
			(layer "B.Fab")
		)
		(fp_line
			(start -1.1049 -0.724916)
			(end 1.1049 -0.724916)
			(stroke
				(width 0.1)
				(type default)
			)
			(layer "B.Fab")
		)
		(fp_line
			(start 1.1049 0.724916)
			(end -1.1049 0.724916)
			(stroke
				(width 0.1)
				(type default)
			)
			(layer "B.Fab")
		)
		(fp_line
			(start -1.1049 0.724916)
			(end -1.1049 -0.724916)
			(stroke
				(width 0.1)
				(type default)
			)
			(layer "B.Fab")
		)
		(pad "1" smd rect
			(at 0.889 0 90)
			(size 1.016 1.27)
			(layers "B.Cu" "B.Mask" "B.Paste")
			(net "SW_P12V_PVCCIN_CPU0_FLT")
		)
		(pad "2" smd rect
			(at -0.889 0 90)
			(size 1.016 1.27)
			(layers "B.Cu" "B.Mask" "B.Paste")
			(net "GND")
		)
	)
	(footprint ""
		(layer "B.Cu")
		(at 131.93522 -24.100028 180)
		(property "Reference" "C2289"
			(at 0 0 0)
			(layer "B.SilkS")
			(hide yes)
			(effects
				(font
					(size 1.27 1.27)
				)
				(justify mirror)
			)
		)
		(property "Value" ""
			(at 0 0 0)
			(layer "B.Fab")
			(effects
				(font
					(size 1.27 1.27)
				)
				(justify mirror)
			)
		)
		(duplicate_pad_numbers_are_jumpers no)
		(fp_line
			(start 0.299974 0.150114)
			(end 0.299974 -0.150114)
			(stroke
				(width 0.1)
				(type default)
			)
			(layer "B.Fab")
		)
		(fp_line
			(start 0.299974 -0.150114)
			(end -0.299974 -0.150114)
			(stroke
				(width 0.1)
				(type default)
			)
			(layer "B.Fab")
		)
		(fp_line
			(start -0.299974 0.150114)
			(end 0.299974 0.150114)
			(stroke
				(width 0.1)
				(type default)
			)
			(layer "B.Fab")
		)
		(fp_line
			(start -0.299974 -0.150114)
			(end -0.299974 0.150114)
			(stroke
				(width 0.1)
				(type default)
			)
			(layer "B.Fab")
		)
		(pad "1" smd rect
			(at 0.2667 0)
			(size 0.3048 0.381)
			(layers "B.Cu" "B.Mask" "B.Paste")
			(net "USB3_PCH_TX_BUF_DP<4>")
		)
		(pad "2" smd rect
			(at -0.2667 0)
			(size 0.3048 0.381)
			(layers "B.Cu" "B.Mask" "B.Paste")
			(net "USB3_PCH_TX_BUF_C_DP<4>")
		)
	)
)
